(kicad_pcb
	(version 20260206)
	(generator "pcbnew")
	(generator_version "10.0")
	(general
		(thickness 1.6)
		(legacy_teardrops no)
	)
	(paper "A4")
	(title_block
		(title "01162023_DA0F0TEBIF0_F0T_Expander_BD_F_brd_V02_OCP.brd")
		(comment 1 "Grand Teton / footprints 9364-9372 of 9728")
	)
	(layers
		(0 "F.Cu" signal "TOP")
		(4 "In1.Cu" signal "GND")
		(6 "In2.Cu" signal "VCC")
		(8 "In3.Cu" signal "VCC1")
		(10 "In4.Cu" signal "GND1")
		(12 "In5.Cu" signal "IN1")
		(14 "In6.Cu" signal "GND2")
		(16 "In7.Cu" signal "IN2")
		(18 "In8.Cu" signal "GND3")
		(20 "In9.Cu" signal "IN3")
		(22 "In10.Cu" signal "GND4")
		(24 "In11.Cu" signal "IN4")
		(26 "In12.Cu" signal "GND5")
		(28 "In13.Cu" signal "IN5")
		(30 "In14.Cu" signal "GND6")
		(32 "In15.Cu" signal "IN6")
		(34 "In16.Cu" signal "GND7")
		(2 "B.Cu" signal "BOTTOM")
		(9 "F.Adhes" user "F.Adhesive")
		(11 "B.Adhes" user "B.Adhesive")
		(13 "F.Paste" user "Package Geometry/Pastemask Top")
		(15 "B.Paste" user "Package Geometry/Pastemask Bottom")
		(5 "F.SilkS" user "Ref Des/Silkscreen Top")
		(7 "B.SilkS" user "Ref Des/Silkscreen Bottom")
		(1 "F.Mask" user "Board Geometry/Soldermask Top")
		(3 "B.Mask" user "Board Geometry/Soldermask Bottom")
		(17 "Dwgs.User" user "User.Drawings")
		(19 "Cmts.User" user "User.Comments")
		(21 "Eco1.User" user "User.Eco1")
		(23 "Eco2.User" user "User.Eco2")
		(25 "Edge.Cuts" user "Board Geometry/Outline")
		(27 "Margin" user)
		(31 "F.CrtYd" user "Package Geometry/Place Bound Top")
		(29 "B.CrtYd" user "Package Geometry/Place Bound Bottom")
		(35 "F.Fab" user "Ref Des/Assembly Top")
		(33 "B.Fab" user "Ref Des/Assembly Bottom")
	)
	(footprint ""
		(layer "B.Cu")
		(at 234.13466 -207.02016 -90)
		(property "Reference" "R4860"
			(at 0 0 90)
			(layer "B.SilkS")
			(hide yes)
			(effects
				(font
					(size 1.27 1.27)
				)
				(justify mirror)
			)
		)
		(property "Value" ""
			(at 0 0 90)
			(layer "B.Fab")
			(effects
				(font
					(size 1.27 1.27)
				)
				(justify mirror)
			)
		)
		(duplicate_pad_numbers_are_jumpers no)
		(fp_line
			(start -0.7874 0.4064)
			(end 0.7874 0.4064)
			(stroke
				(width 0.1524)
				(type default)
			)
			(layer "B.SilkS")
		)
		(fp_line
			(start 0.7874 0.4064)
			(end 0.7874 -0.4064)
			(stroke
				(width 0.1524)
				(type default)
			)
			(layer "B.SilkS")
		)
		(fp_line
			(start -0.7874 -0.4064)
			(end -0.7874 0.4064)
			(stroke
				(width 0.1524)
				(type default)
			)
			(layer "B.SilkS")
		)
		(fp_line
			(start 0.7874 -0.4064)
			(end -0.7874 -0.4064)
			(stroke
				(width 0.1524)
				(type default)
			)
			(layer "B.SilkS")
		)
		(fp_line
			(start -0.67945 0.3048)
			(end -0.120396 0.3048)
			(stroke
				(width 0.1)
				(type default)
			)
			(layer "B.Fab")
		)
		(fp_line
			(start -0.120396 0.3048)
			(end -0.120396 0.2794)
			(stroke
				(width 0.1)
				(type default)
			)
			(layer "B.Fab")
		)
		(fp_line
			(start 0.12065 0.3048)
			(end 0.67945 0.3048)
			(stroke
				(width 0.1)
				(type default)
			)
			(layer "B.Fab")
		)
		(fp_line
			(start 0.67945 0.3048)
			(end 0.67945 -0.305054)
			(stroke
				(width 0.1)
				(type default)
			)
			(layer "B.Fab")
		)
		(fp_line
			(start -0.120396 0.2794)
			(end 0.12065 0.2794)
			(stroke
				(width 0.1)
				(type default)
			)
			(layer "B.Fab")
		)
		(fp_line
			(start 0.12065 0.2794)
			(end 0.12065 0.3048)
			(stroke
				(width 0.1)
				(type default)
			)
			(layer "B.Fab")
		)
		(fp_line
			(start -0.12065 -0.2794)
			(end -0.12065 -0.3048)
			(stroke
				(width 0.1)
				(type default)
			)
			(layer "B.Fab")
		)
		(fp_line
			(start 0.12065 -0.2794)
			(end -0.12065 -0.2794)
			(stroke
				(width 0.1)
				(type default)
			)
			(layer "B.Fab")
		)
		(fp_line
			(start -0.67945 -0.3048)
			(end -0.67945 0.3048)
			(stroke
				(width 0.1)
				(type default)
			)
			(layer "B.Fab")
		)
		(fp_line
			(start -0.12065 -0.3048)
			(end -0.67945 -0.3048)
			(stroke
				(width 0.1)
				(type default)
			)
			(layer "B.Fab")
		)
		(fp_line
			(start 0.12065 -0.305054)
			(end 0.12065 -0.2794)
			(stroke
				(width 0.1)
				(type default)
			)
			(layer "B.Fab")
		)
		(fp_line
			(start 0.67945 -0.305054)
			(end 0.12065 -0.305054)
			(stroke
				(width 0.1)
				(type default)
			)
			(layer "B.Fab")
		)
		(pad "1" smd circle
			(at 0.40005 0 90)
			(size 0 0)
			(layers "B.Cu" "B.Mask" "B.Paste")
			(net "CLK_25M_BIC")
		)
		(pad "2" smd circle
			(at -0.40005 0 90)
			(size 0 0)
			(layers "B.Cu" "B.Mask" "B.Paste")
			(net "CLK_25M_BIC_CLKIN")
		)
	)
	(footprint ""
		(layer "B.Cu")
		(at 67.249802 -290.199826 90)
		(property "Reference" "C1169"
			(at 0 0 90)
			(layer "B.SilkS")
			(hide yes)
			(effects
				(font
					(size 1.27 1.27)
				)
				(justify mirror)
			)
		)
		(property "Value" ""
			(at 0 0 90)
			(layer "B.Fab")
			(effects
				(font
					(size 1.27 1.27)
				)
				(justify mirror)
			)
		)
		(duplicate_pad_numbers_are_jumpers no)
		(fp_line
			(start 0.299974 -0.150114)
			(end -0.299974 -0.150114)
			(stroke
				(width 0.1)
				(type default)
			)
			(layer "B.Fab")
		)
		(fp_line
			(start -0.299974 -0.150114)
			(end -0.299974 0.150114)
			(stroke
				(width 0.1)
				(type default)
			)
			(layer "B.Fab")
		)
		(fp_line
			(start 0.299974 0.150114)
			(end 0.299974 -0.150114)
			(stroke
				(width 0.1)
				(type default)
			)
			(layer "B.Fab")
		)
		(fp_line
			(start -0.299974 0.150114)
			(end 0.299974 0.150114)
			(stroke
				(width 0.1)
				(type default)
			)
			(layer "B.Fab")
		)
		(pad "1" smd rect
			(at 0.2667 0 270)
			(size 0.3048 0.381)
			(layers "B.Cu" "B.Mask" "B.Paste")
			(net "P0V8_SERDES_VDDA_PEX0")
		)
		(pad "2" smd rect
			(at -0.2667 0 270)
			(size 0.3048 0.381)
			(layers "B.Cu" "B.Mask" "B.Paste")
			(net "GND")
		)
	)
	(footprint ""
		(layer "B.Cu")
		(at 307.923692 -289.724846 90)
		(property "Reference" "R965"
			(at 0 0 90)
			(layer "B.SilkS")
			(hide yes)
			(effects
				(font
					(size 1.27 1.27)
				)
				(justify mirror)
			)
		)
		(property "Value" ""
			(at 0 0 90)
			(layer "B.Fab")
			(effects
				(font
					(size 1.27 1.27)
				)
				(justify mirror)
			)
		)
		(duplicate_pad_numbers_are_jumpers no)
		(fp_line
			(start 0.7874 -0.4064)
			(end -0.7874 -0.4064)
			(stroke
				(width 0.1524)
				(type default)
			)
			(layer "B.SilkS")
		)
		(fp_line
			(start -0.7874 -0.4064)
			(end -0.7874 0.4064)
			(stroke
				(width 0.1524)
				(type default)
			)
			(layer "B.SilkS")
		)
		(fp_line
			(start 0.7874 0.4064)
			(end 0.7874 -0.4064)
			(stroke
				(width 0.1524)
				(type default)
			)
			(layer "B.SilkS")
		)
		(fp_line
			(start -0.7874 0.4064)
			(end 0.7874 0.4064)
			(stroke
				(width 0.1524)
				(type default)
			)
			(layer "B.SilkS")
		)
		(fp_line
			(start 0.67945 -0.305054)
			(end 0.12065 -0.305054)
			(stroke
				(width 0.1)
				(type default)
			)
			(layer "B.Fab")
		)
		(fp_line
			(start 0.12065 -0.305054)
			(end 0.12065 -0.2794)
			(stroke
				(width 0.1)
				(type default)
			)
			(layer "B.Fab")
		)
		(fp_line
			(start -0.12065 -0.3048)
			(end -0.67945 -0.3048)
			(stroke
				(width 0.1)
				(type default)
			)
			(layer "B.Fab")
		)
		(fp_line
			(start -0.67945 -0.3048)
			(end -0.67945 0.3048)
			(stroke
				(width 0.1)
				(type default)
			)
			(layer "B.Fab")
		)
		(fp_line
			(start 0.12065 -0.2794)
			(end -0.12065 -0.2794)
			(stroke
				(width 0.1)
				(type default)
			)
			(layer "B.Fab")
		)
		(fp_line
			(start -0.12065 -0.2794)
			(end -0.12065 -0.3048)
			(stroke
				(width 0.1)
				(type default)
			)
			(layer "B.Fab")
		)
		(fp_line
			(start 0.12065 0.2794)
			(end 0.12065 0.3048)
			(stroke
				(width 0.1)
				(type default)
			)
			(layer "B.Fab")
		)
		(fp_line
			(start -0.120396 0.2794)
			(end 0.12065 0.2794)
			(stroke
				(width 0.1)
				(type default)
			)
			(layer "B.Fab")
		)
		(fp_line
			(start 0.67945 0.3048)
			(end 0.67945 -0.305054)
			(stroke
				(width 0.1)
				(type default)
			)
			(layer "B.Fab")
		)
		(fp_line
			(start 0.12065 0.3048)
			(end 0.67945 0.3048)
			(stroke
				(width 0.1)
				(type default)
			)
			(layer "B.Fab")
		)
		(fp_line
			(start -0.120396 0.3048)
			(end -0.120396 0.2794)
			(stroke
				(width 0.1)
				(type default)
			)
			(layer "B.Fab")
		)
		(fp_line
			(start -0.67945 0.3048)
			(end -0.120396 0.3048)
			(stroke
				(width 0.1)
				(type default)
			)
			(layer "B.Fab")
		)
		(pad "1" smd circle
			(at 0.40005 0 270)
			(size 0 0)
			(layers "B.Cu" "B.Mask" "B.Paste")
			(net "UART_PEX2_SDB_TX")
		)
		(pad "2" smd circle
			(at -0.40005 0 270)
			(size 0 0)
			(layers "B.Cu" "B.Mask" "B.Paste")
			(net "UART_PEX2_SDB_R_TX")
		)
	)
	(footprint ""
		(layer "B.Cu")
		(at 113.121186 -284.796738 -90)
		(property "Reference" "PC60"
			(at 0 0 90)
			(layer "B.SilkS")
			(hide yes)
			(effects
				(font
					(size 1.27 1.27)
				)
				(justify mirror)
			)
		)
		(property "Value" ""
			(at 0 0 90)
			(layer "B.Fab")
			(effects
				(font
					(size 1.27 1.27)
				)
				(justify mirror)
			)
		)
		(duplicate_pad_numbers_are_jumpers no)
		(fp_line
			(start -1.524 0.762)
			(end 1.524 0.762)
			(stroke
				(width 0.1524)
				(type default)
			)
			(layer "B.SilkS")
		)
		(fp_line
			(start 1.524 0.762)
			(end 1.524 -0.762)
			(stroke
				(width 0.1524)
				(type default)
			)
			(layer "B.SilkS")
		)
		(fp_line
			(start -1.524 -0.762)
			(end -1.524 0.762)
			(stroke
				(width 0.1524)
				(type default)
			)
			(layer "B.SilkS")
		)
		(fp_line
			(start 1.524 -0.762)
			(end -1.524 -0.762)
			(stroke
				(width 0.1524)
				(type default)
			)
			(layer "B.SilkS")
		)
		(fp_line
			(start -1.1049 0.724916)
			(end -1.1049 -0.724916)
			(stroke
				(width 0.1)
				(type default)
			)
			(layer "B.Fab")
		)
		(fp_line
			(start 1.1049 0.724916)
			(end -1.1049 0.724916)
			(stroke
				(width 0.1)
				(type default)
			)
			(layer "B.Fab")
		)
		(fp_line
			(start -1.1049 -0.724916)
			(end 1.1049 -0.724916)
			(stroke
				(width 0.1)
				(type default)
			)
			(layer "B.Fab")
		)
		(fp_line
			(start 1.1049 -0.724916)
			(end 1.1049 0.724916)
			(stroke
				(width 0.1)
				(type default)
			)
			(layer "B.Fab")
		)
		(pad "1" smd rect
			(at 0.889 0 270)
			(size 1.016 1.27)
			(layers "B.Cu" "B.Mask" "B.Paste")
			(net "SW_P12V_P0V8_PEX0_FLT")
		)
		(pad "2" smd rect
			(at -0.889 0 270)
			(size 1.016 1.27)
			(layers "B.Cu" "B.Mask" "B.Paste")
			(net "GND")
		)
	)
	(footprint ""
		(layer "B.Cu")
		(at 105.380536 -392.988292)
		(property "Reference" "C3634"
			(at 0 0 0)
			(layer "B.SilkS")
			(hide yes)
			(effects
				(font
					(size 1.27 1.27)
				)
				(justify mirror)
			)
		)
		(property "Value" ""
			(at 0 0 0)
			(layer "B.Fab")
			(effects
				(font
					(size 1.27 1.27)
				)
				(justify mirror)
			)
		)
		(duplicate_pad_numbers_are_jumpers no)
		(fp_line
			(start -0.7874 -0.4064)
			(end -0.7874 0.4064)
			(stroke
				(width 0.1524)
				(type default)
			)
			(layer "B.SilkS")
		)
		(fp_line
			(start -0.7874 0.4064)
			(end 0.7874 0.4064)
			(stroke
				(width 0.1524)
				(type default)
			)
			(layer "B.SilkS")
		)
		(fp_line
			(start 0.7874 -0.4064)
			(end -0.7874 -0.4064)
			(stroke
				(width 0.1524)
				(type default)
			)
			(layer "B.SilkS")
		)
		(fp_line
			(start 0.7874 0.4064)
			(end 0.7874 -0.4064)
			(stroke
				(width 0.1524)
				(type default)
			)
			(layer "B.SilkS")
		)
		(fp_line
			(start -0.67945 -0.3048)
			(end -0.67945 0.3048)
			(stroke
				(width 0.1)
				(type default)
			)
			(layer "B.Fab")
		)
		(fp_line
			(start -0.67945 0.3048)
			(end -0.120396 0.3048)
			(stroke
				(width 0.1)
				(type default)
			)
			(layer "B.Fab")
		)
		(fp_line
			(start -0.12065 -0.3048)
			(end -0.67945 -0.3048)
			(stroke
				(width 0.1)
				(type default)
			)
			(layer "B.Fab")
		)
		(fp_line
			(start -0.12065 -0.2794)
			(end -0.12065 -0.3048)
			(stroke
				(width 0.1)
				(type default)
			)
			(layer "B.Fab")
		)
		(fp_line
			(start -0.120396 0.2794)
			(end 0.12065 0.2794)
			(stroke
				(width 0.1)
				(type default)
			)
			(layer "B.Fab")
		)
		(fp_line
			(start -0.120396 0.3048)
			(end -0.120396 0.2794)
			(stroke
				(width 0.1)
				(type default)
			)
			(layer "B.Fab")
		)
		(fp_line
			(start 0.12065 -0.305054)
			(end 0.12065 -0.2794)
			(stroke
				(width 0.1)
				(type default)
			)
			(layer "B.Fab")
		)
		(fp_line
			(start 0.12065 -0.2794)
			(end -0.12065 -0.2794)
			(stroke
				(width 0.1)
				(type default)
			)
			(layer "B.Fab")
		)
		(fp_line
			(start 0.12065 0.2794)
			(end 0.12065 0.3048)
			(stroke
				(width 0.1)
				(type default)
			)
			(layer "B.Fab")
		)
		(fp_line
			(start 0.12065 0.3048)
			(end 0.67945 0.3048)
			(stroke
				(width 0.1)
				(type default)
			)
			(layer "B.Fab")
		)
		(fp_line
			(start 0.67945 -0.305054)
			(end 0.12065 -0.305054)
			(stroke
				(width 0.1)
				(type default)
			)
			(layer "B.Fab")
		)
		(fp_line
			(start 0.67945 0.3048)
			(end 0.67945 -0.305054)
			(stroke
				(width 0.1)
				(type default)
			)
			(layer "B.Fab")
		)
		(pad "1" smd circle
			(at 0.40005 0 180)
			(size 0 0)
			(layers "B.Cu" "B.Mask" "B.Paste")
			(net "P3V3_BIC_USB_HUB")
		)
		(pad "2" smd circle
			(at -0.40005 0 180)
			(size 0 0)
			(layers "B.Cu" "B.Mask" "B.Paste")
			(net "GND")
		)
	)
	(footprint ""
		(layer "B.Cu")
		(at 232.083864 -204.44206 -90)
		(property "Reference" "R5526"
			(at 0 0 90)
			(layer "B.SilkS")
			(hide yes)
			(effects
				(font
					(size 1.27 1.27)
				)
				(justify mirror)
			)
		)
		(property "Value" ""
			(at 0 0 90)
			(layer "B.Fab")
			(effects
				(font
					(size 1.27 1.27)
				)
				(justify mirror)
			)
		)
		(duplicate_pad_numbers_are_jumpers no)
		(fp_line
			(start -0.7874 0.4064)
			(end 0.7874 0.4064)
			(stroke
				(width 0.1524)
				(type default)
			)
			(layer "B.SilkS")
		)
		(fp_line
			(start 0.7874 0.4064)
			(end 0.7874 -0.4064)
			(stroke
				(width 0.1524)
				(type default)
			)
			(layer "B.SilkS")
		)
		(fp_line
			(start -0.7874 -0.4064)
			(end -0.7874 0.4064)
			(stroke
				(width 0.1524)
				(type default)
			)
			(layer "B.SilkS")
		)
		(fp_line
			(start 0.7874 -0.4064)
			(end -0.7874 -0.4064)
			(stroke
				(width 0.1524)
				(type default)
			)
			(layer "B.SilkS")
		)
		(fp_line
			(start -0.67945 0.3048)
			(end -0.120396 0.3048)
			(stroke
				(width 0.1)
				(type default)
			)
			(layer "B.Fab")
		)
		(fp_line
			(start -0.120396 0.3048)
			(end -0.120396 0.2794)
			(stroke
				(width 0.1)
				(type default)
			)
			(layer "B.Fab")
		)
		(fp_line
			(start 0.12065 0.3048)
			(end 0.67945 0.3048)
			(stroke
				(width 0.1)
				(type default)
			)
			(layer "B.Fab")
		)
		(fp_line
			(start 0.67945 0.3048)
			(end 0.67945 -0.305054)
			(stroke
				(width 0.1)
				(type default)
			)
			(layer "B.Fab")
		)
		(fp_line
			(start -0.120396 0.2794)
			(end 0.12065 0.2794)
			(stroke
				(width 0.1)
				(type default)
			)
			(layer "B.Fab")
		)
		(fp_line
			(start 0.12065 0.2794)
			(end 0.12065 0.3048)
			(stroke
				(width 0.1)
				(type default)
			)
			(layer "B.Fab")
		)
		(fp_line
			(start -0.12065 -0.2794)
			(end -0.12065 -0.3048)
			(stroke
				(width 0.1)
				(type default)
			)
			(layer "B.Fab")
		)
		(fp_line
			(start 0.12065 -0.2794)
			(end -0.12065 -0.2794)
			(stroke
				(width 0.1)
				(type default)
			)
			(layer "B.Fab")
		)
		(fp_line
			(start -0.67945 -0.3048)
			(end -0.67945 0.3048)
			(stroke
				(width 0.1)
				(type default)
			)
			(layer "B.Fab")
		)
		(fp_line
			(start -0.12065 -0.3048)
			(end -0.67945 -0.3048)
			(stroke
				(width 0.1)
				(type default)
			)
			(layer "B.Fab")
		)
		(fp_line
			(start 0.12065 -0.305054)
			(end 0.12065 -0.2794)
			(stroke
				(width 0.1)
				(type default)
			)
			(layer "B.Fab")
		)
		(fp_line
			(start 0.67945 -0.305054)
			(end 0.12065 -0.305054)
			(stroke
				(width 0.1)
				(type default)
			)
			(layer "B.Fab")
		)
		(pad "1" smd circle
			(at 0.40005 0 90)
			(size 0 0)
			(layers "B.Cu" "B.Mask" "B.Paste")
			(net "GND")
		)
		(pad "2" smd circle
			(at -0.40005 0 90)
			(size 0 0)
			(layers "B.Cu" "B.Mask" "B.Paste")
			(net "BIC_FWSPIMISO")
		)
	)
	(footprint ""
		(layer "B.Cu")
		(at 173.850046 -292.099746 90)
		(property "Reference" "C1488"
			(at 0 0 90)
			(layer "B.SilkS")
			(hide yes)
			(effects
				(font
					(size 1.27 1.27)
				)
				(justify mirror)
			)
		)
		(property "Value" ""
			(at 0 0 90)
			(layer "B.Fab")
			(effects
				(font
					(size 1.27 1.27)
				)
				(justify mirror)
			)
		)
		(duplicate_pad_numbers_are_jumpers no)
		(fp_line
			(start 0.299974 -0.150114)
			(end -0.299974 -0.150114)
			(stroke
				(width 0.1)
				(type default)
			)
			(layer "B.Fab")
		)
		(fp_line
			(start -0.299974 -0.150114)
			(end -0.299974 0.150114)
			(stroke
				(width 0.1)
				(type default)
			)
			(layer "B.Fab")
		)
		(fp_line
			(start 0.299974 0.150114)
			(end 0.299974 -0.150114)
			(stroke
				(width 0.1)
				(type default)
			)
			(layer "B.Fab")
		)
		(fp_line
			(start -0.299974 0.150114)
			(end 0.299974 0.150114)
			(stroke
				(width 0.1)
				(type default)
			)
			(layer "B.Fab")
		)
		(pad "1" smd rect
			(at 0.2667 0 270)
			(size 0.3048 0.381)
			(layers "B.Cu" "B.Mask" "B.Paste")
			(net "P0V8_SERDES_VDDA_PEX1")
		)
		(pad "2" smd rect
			(at -0.2667 0 270)
			(size 0.3048 0.381)
			(layers "B.Cu" "B.Mask" "B.Paste")
			(net "GND")
		)
	)
	(footprint ""
		(layer "B.Cu")
		(at 419.349936 -294.4749 180)
		(property "Reference" "C3464"
			(at 0 0 0)
			(layer "B.SilkS")
			(hide yes)
			(effects
				(font
					(size 1.27 1.27)
				)
				(justify mirror)
			)
		)
		(property "Value" ""
			(at 0 0 0)
			(layer "B.Fab")
			(effects
				(font
					(size 1.27 1.27)
				)
				(justify mirror)
			)
		)
		(duplicate_pad_numbers_are_jumpers no)
		(fp_line
			(start 0.299974 0.150114)
			(end 0.299974 -0.150114)
			(stroke
				(width 0.1)
				(type default)
			)
			(layer "B.Fab")
		)
		(fp_line
			(start 0.299974 -0.150114)
			(end -0.299974 -0.150114)
			(stroke
				(width 0.1)
				(type default)
			)
			(layer "B.Fab")
		)
		(fp_line
			(start -0.299974 0.150114)
			(end 0.299974 0.150114)
			(stroke
				(width 0.1)
				(type default)
			)
			(layer "B.Fab")
		)
		(fp_line
			(start -0.299974 -0.150114)
			(end -0.299974 0.150114)
			(stroke
				(width 0.1)
				(type default)
			)
			(layer "B.Fab")
		)
		(pad "1" smd rect
			(at 0.2667 0)
			(size 0.3048 0.381)
			(layers "B.Cu" "B.Mask" "B.Paste")
			(net "P1V25_PEX3")
		)
		(pad "2" smd rect
			(at -0.2667 0)
			(size 0.3048 0.381)
			(layers "B.Cu" "B.Mask" "B.Paste")
			(net "GND")
		)
	)
	(footprint ""
		(layer "B.Cu")
		(at 411.750002 -290.199826 90)
		(property "Reference" "C1966"
			(at 0 0 90)
			(layer "B.SilkS")
			(hide yes)
			(effects
				(font
					(size 1.27 1.27)
				)
				(justify mirror)
			)
		)
		(property "Value" ""
			(at 0 0 90)
			(layer "B.Fab")
			(effects
				(font
					(size 1.27 1.27)
				)
				(justify mirror)
			)
		)
		(duplicate_pad_numbers_are_jumpers no)
		(fp_line
			(start 0.299974 -0.150114)
			(end -0.299974 -0.150114)
			(stroke
				(width 0.1)
				(type default)
			)
			(layer "B.Fab")
		)
		(fp_line
			(start -0.299974 -0.150114)
			(end -0.299974 0.150114)
			(stroke
				(width 0.1)
				(type default)
			)
			(layer "B.Fab")
		)
		(fp_line
			(start 0.299974 0.150114)
			(end 0.299974 -0.150114)
			(stroke
				(width 0.1)
				(type default)
			)
			(layer "B.Fab")
		)
		(fp_line
			(start -0.299974 0.150114)
			(end 0.299974 0.150114)
			(stroke
				(width 0.1)
				(type default)
			)
			(layer "B.Fab")
		)
		(pad "1" smd rect
			(at 0.2667 0 270)
			(size 0.3048 0.381)
			(layers "B.Cu" "B.Mask" "B.Paste")
			(net "P0V8_SERDES_VDDA_PEX3")
		)
		(pad "2" smd rect
			(at -0.2667 0 270)
			(size 0.3048 0.381)
			(layers "B.Cu" "B.Mask" "B.Paste")
			(net "GND")
		)
	)
)
